(kicad_pcb
	(version 20260206)
	(generator "pcbnew")
	(generator_version "10.0")
	(general
		(thickness 1.6)
		(legacy_teardrops no)
	)
	(paper "A4")
	(title_block
		(title "Wiwynn_Tioga_Pass_MB.brd")
		(comment 1 "Tioga Pass / footprints 206-212 of 4770")
	)
	(layers
		(0 "F.Cu" signal "TOP")
		(4 "In1.Cu" signal "L2GND")
		(6 "In2.Cu" signal "L3")
		(8 "In3.Cu" signal "L4GND")
		(10 "In4.Cu" signal "L5")
		(12 "In5.Cu" signal "L6GND")
		(14 "In6.Cu" signal "L7VCC")
		(16 "In7.Cu" signal "L8VCC")
		(18 "In8.Cu" signal "L9GND")
		(20 "In9.Cu" signal "L10")
		(22 "In10.Cu" signal "L11GND")
		(24 "In11.Cu" signal "L12")
		(26 "In12.Cu" signal "L13GND")
		(2 "B.Cu" signal "BOTTOM")
		(9 "F.Adhes" user "F.Adhesive")
		(11 "B.Adhes" user "B.Adhesive")
		(13 "F.Paste" user "Package Geometry/Pastemask Top")
		(15 "B.Paste" user "Package Geometry/Pastemask Bottom")
		(5 "F.SilkS" user "Ref Des/Silkscreen Top")
		(7 "B.SilkS" user "Ref Des/Silkscreen Bottom")
		(1 "F.Mask" user "Board Geometry/Soldermask Top")
		(3 "B.Mask" user "Board Geometry/Soldermask Bottom")
		(17 "Dwgs.User" user "User.Drawings")
		(19 "Cmts.User" user "User.Comments")
		(21 "Eco1.User" user "User.Eco1")
		(23 "Eco2.User" user "User.Eco2")
		(25 "Edge.Cuts" user "Board Geometry/Outline")
		(27 "Margin" user)
		(31 "F.CrtYd" user "Package Geometry/Place Bound Top")
		(29 "B.CrtYd" user "Package Geometry/Place Bound Bottom")
		(35 "F.Fab" user "Ref Des/Assembly Top")
		(33 "B.Fab" user "Ref Des/Assembly Bottom")
	)
	(footprint ""
		(layer "F.Cu")
		(at 6.820916 -5.552948 -90)
		(property "Reference" "RT20"
			(at 0 0 270)
			(layer "F.SilkS")
			(hide yes)
			(effects
				(font
					(size 1.27 1.27)
				)
			)
		)
		(property "Value" "*"
			(at -0.0254 -2.6289 270)
			(unlocked yes)
			(layer "F.Fab")
			(hide yes)
			(effects
				(font
					(size 1.27 1.016)
					(thickness 0.1524)
				)
			)
		)
		(property "Device Type" "1R3F-GP_RCL_GP-1R3F-GP,64.1R00A"
			(at -0.0254 -4.1529 270)
			(unlocked yes)
			(layer "F.Fab")
			(hide yes)
			(effects
				(font
					(size 1.27 1.016)
					(thickness 0.1524)
				)
			)
		)
		(duplicate_pad_numbers_are_jumpers no)
		(fp_line
			(start -0.4826 0)
			(end -0.2032 0)
			(stroke
				(width 0.2032)
				(type default)
			)
			(layer "F.SilkS")
		)
		(fp_line
			(start 0.2032 0)
			(end 0.4826 0)
			(stroke
				(width 0.2032)
				(type default)
			)
			(layer "F.SilkS")
		)
		(fp_rect
			(start -0.5842 1.3335)
			(end 0.5842 -1.3335)
			(stroke
				(width 0)
				(type default)
			)
			(fill no)
			(layer "F.CrtYd")
		)
		(fp_rect
			(start -0.5842 1.3335)
			(end 0.5842 -1.3335)
			(stroke
				(width 0)
				(type default)
			)
			(fill no)
			(layer "F.Fab")
		)
		(pad "1" smd custom
			(at 0 -0.762 270)
			(size 0.2159 0.2159)
			(layers "F.Cu" "F.Mask" "F.Paste")
			(net "VR_PVDDQ_GHJ_PH1_SW_RC")
			(options
				(clearance outline)
				(anchor circle)
			)
			(primitives
				(gr_poly
					(pts
						(arc
							(start -0.3302 -0.4318)
							(mid -0.402042 -0.402042)
							(end -0.4318 -0.3302)
						)
						(arc
							(start -0.4318 0.3302)
							(mid -0.402042 0.402042)
							(end -0.3302 0.4318)
						)
						(arc
							(start 0.3302 0.4318)
							(mid 0.402042 0.402042)
							(end 0.4318 0.3302)
						)
						(arc
							(start 0.4318 -0.3302)
							(mid 0.402042 -0.402042)
							(end 0.3302 -0.4318)
						)
					)
					(width 0)
					(fill yes)
				)
			)
		)
		(pad "2" smd custom
			(at 0 0.762 270)
			(size 0.2159 0.2159)
			(layers "F.Cu" "F.Mask" "F.Paste")
			(net "GND")
			(options
				(clearance outline)
				(anchor circle)
			)
			(primitives
				(gr_poly
					(pts
						(arc
							(start -0.3302 -0.4318)
							(mid -0.402042 -0.402042)
							(end -0.4318 -0.3302)
						)
						(arc
							(start -0.4318 0.3302)
							(mid -0.402042 0.402042)
							(end -0.3302 0.4318)
						)
						(arc
							(start 0.3302 0.4318)
							(mid 0.402042 0.402042)
							(end 0.4318 0.3302)
						)
						(arc
							(start 0.4318 -0.3302)
							(mid 0.402042 -0.402042)
							(end 0.3302 -0.4318)
						)
					)
					(width 0)
					(fill yes)
				)
			)
		)
	)
	(footprint ""
		(layer "F.Cu")
		(at 472.313 -30.607 90)
		(property "Reference" "R1W22"
			(at -0.8382 -0.67818 90)
			(unlocked yes)
			(layer "F.SilkS")
			(effects
				(font
					(size 0.4064 0.254)
					(thickness 0.1524)
				)
				(justify left)
			)
		)
		(property "Value" ""
			(at 0 0 90)
			(layer "F.Fab")
			(effects
				(font
					(size 1.27 1.27)
				)
			)
		)
		(duplicate_pad_numbers_are_jumpers no)
		(fp_poly
			(pts
				(xy -0.2794 -0.1016) (xy 0.2794 -0.1016) (xy 0.2794 0.9906) (xy -0.2794 0.9906)
			)
			(stroke
				(width 0)
				(type default)
			)
			(fill no)
			(layer "F.CrtYd")
		)
		(fp_line
			(start 0.2794 -0.1016)
			(end -0.2794 -0.1016)
			(stroke
				(width 0.1)
				(type default)
			)
			(layer "F.Fab")
		)
		(fp_line
			(start -0.2794 -0.1016)
			(end -0.2794 0.9906)
			(stroke
				(width 0.1)
				(type default)
			)
			(layer "F.Fab")
		)
		(fp_line
			(start 0.2794 0.9906)
			(end 0.2794 -0.1016)
			(stroke
				(width 0.1)
				(type default)
			)
			(layer "F.Fab")
		)
		(fp_line
			(start -0.2794 0.9906)
			(end 0.2794 0.9906)
			(stroke
				(width 0.1)
				(type default)
			)
			(layer "F.Fab")
		)
		(pad "1" smd rect
			(at 0 0 90)
			(size 0.508 0.508)
			(layers "F.Cu" "F.Mask" "F.Paste")
			(net "SMB_HOST_STBY_LVC3_SCL")
		)
		(pad "2" smd rect
			(at 0 0.889 90)
			(size 0.508 0.508)
			(layers "F.Cu" "F.Mask" "F.Paste")
			(net "SMB_HOST_STBY_LVC3_SCL_R4")
		)
		(zone
			(layer "F.Cu")
			(hatch none 0.5)
			(connect_pads
				(clearance 0)
			)
			(min_thickness 0.25)
			(keepout
				(tracks allowed)
				(vias not_allowed)
				(pads allowed)
				(copperpour not_allowed)
				(footprints allowed)
			)
			(placement
				(enabled no)
				(sheetname "")
			)
			(fill
				(thermal_gap 0.5)
				(thermal_bridge_width 0.5)
				(island_removal_mode 0)
			)
			(polygon
				(pts
					(xy 472.567 -30.353) (xy 472.567 -30.861) (xy 472.948 -30.861) (xy 472.948 -30.353)
				)
			)
		)
		(zone
			(layer "F.Cu")
			(hatch none 0.5)
			(connect_pads
				(clearance 0)
			)
			(min_thickness 0.25)
			(keepout
				(tracks not_allowed)
				(vias allowed)
				(pads allowed)
				(copperpour not_allowed)
				(footprints allowed)
			)
			(placement
				(enabled no)
				(sheetname "")
			)
			(fill
				(thermal_gap 0.5)
				(thermal_bridge_width 0.5)
				(island_removal_mode 0)
			)
			(polygon
				(pts
					(xy 472.948 -30.353) (xy 472.948 -30.861) (xy 472.567 -30.861) (xy 472.567 -30.353)
				)
			)
		)
	)
	(footprint ""
		(layer "F.Cu")
		(at 408.319478 -119.051832 90)
		(property "Reference" "R1W14"
			(at -0.8382 -0.67818 90)
			(unlocked yes)
			(layer "F.SilkS")
			(effects
				(font
					(size 0.4064 0.254)
					(thickness 0.1524)
				)
				(justify left)
			)
		)
		(property "Value" ""
			(at 0 0 90)
			(layer "F.Fab")
			(effects
				(font
					(size 1.27 1.27)
				)
			)
		)
		(duplicate_pad_numbers_are_jumpers no)
		(fp_poly
			(pts
				(xy -0.2794 -0.1016) (xy 0.2794 -0.1016) (xy 0.2794 0.9906) (xy -0.2794 0.9906)
			)
			(stroke
				(width 0)
				(type default)
			)
			(fill no)
			(layer "F.CrtYd")
		)
		(fp_line
			(start 0.2794 -0.1016)
			(end -0.2794 -0.1016)
			(stroke
				(width 0.1)
				(type default)
			)
			(layer "F.Fab")
		)
		(fp_line
			(start -0.2794 -0.1016)
			(end -0.2794 0.9906)
			(stroke
				(width 0.1)
				(type default)
			)
			(layer "F.Fab")
		)
		(fp_line
			(start 0.2794 0.9906)
			(end 0.2794 -0.1016)
			(stroke
				(width 0.1)
				(type default)
			)
			(layer "F.Fab")
		)
		(fp_line
			(start -0.2794 0.9906)
			(end 0.2794 0.9906)
			(stroke
				(width 0.1)
				(type default)
			)
			(layer "F.Fab")
		)
		(pad "1" smd rect
			(at 0 0 90)
			(size 0.508 0.508)
			(layers "F.Cu" "F.Mask" "F.Paste")
			(net "USB2_PCH_BMC_P5_DP_R")
		)
		(pad "2" smd rect
			(at 0 0.889 90)
			(size 0.508 0.508)
			(layers "F.Cu" "F.Mask" "F.Paste")
			(net "USB2_PCH_BMC_P5_DP")
		)
		(zone
			(layer "F.Cu")
			(hatch none 0.5)
			(connect_pads
				(clearance 0)
			)
			(min_thickness 0.25)
			(keepout
				(tracks allowed)
				(vias not_allowed)
				(pads allowed)
				(copperpour not_allowed)
				(footprints allowed)
			)
			(placement
				(enabled no)
				(sheetname "")
			)
			(fill
				(thermal_gap 0.5)
				(thermal_bridge_width 0.5)
				(island_removal_mode 0)
			)
			(polygon
				(pts
					(xy 408.573478 -118.797832) (xy 408.573478 -119.305832) (xy 408.954478 -119.305832) (xy 408.954478 -118.797832)
				)
			)
		)
		(zone
			(layer "F.Cu")
			(hatch none 0.5)
			(connect_pads
				(clearance 0)
			)
			(min_thickness 0.25)
			(keepout
				(tracks not_allowed)
				(vias allowed)
				(pads allowed)
				(copperpour not_allowed)
				(footprints allowed)
			)
			(placement
				(enabled no)
				(sheetname "")
			)
			(fill
				(thermal_gap 0.5)
				(thermal_bridge_width 0.5)
				(island_removal_mode 0)
			)
			(polygon
				(pts
					(xy 408.954478 -118.797832) (xy 408.954478 -119.305832) (xy 408.573478 -119.305832) (xy 408.573478 -118.797832)
				)
			)
		)
	)
	(footprint ""
		(layer "F.Cu")
		(at 352.1075 -150.368 90)
		(property "Reference" "C7A11"
			(at 0 0 90)
			(layer "F.SilkS")
			(hide yes)
			(effects
				(font
					(size 1.27 1.27)
				)
			)
		)
		(property "Value" ""
			(at 0 0 90)
			(layer "F.Fab")
			(effects
				(font
					(size 1.27 1.27)
				)
			)
		)
		(duplicate_pad_numbers_are_jumpers no)
		(fp_poly
			(pts
				(xy 0.3048 -0.1016) (xy 0.3048 0.9906) (xy -0.3048 0.9906) (xy -0.3048 -0.1016)
			)
			(stroke
				(width 0)
				(type default)
			)
			(fill no)
			(layer "F.CrtYd")
		)
		(fp_line
			(start 0.3048 -0.1016)
			(end -0.3048 -0.1016)
			(stroke
				(width 0.1)
				(type default)
			)
			(layer "F.Fab")
		)
		(fp_line
			(start -0.3048 -0.1016)
			(end -0.3048 0.9906)
			(stroke
				(width 0.1)
				(type default)
			)
			(layer "F.Fab")
		)
		(fp_line
			(start 0.3048 0.9906)
			(end 0.3048 -0.1016)
			(stroke
				(width 0.1)
				(type default)
			)
			(layer "F.Fab")
		)
		(fp_line
			(start -0.3048 0.9906)
			(end 0.3048 0.9906)
			(stroke
				(width 0.1)
				(type default)
			)
			(layer "F.Fab")
		)
		(pad "1" smd rect
			(at 0 0 90)
			(size 0.508 0.508)
			(layers "F.Cu" "F.Mask" "F.Paste")
			(net "VR_FET_SW_P12V_STBY_PVDDQ_DEF")
		)
		(pad "2" smd rect
			(at 0 0.889 90)
			(size 0.508 0.508)
			(layers "F.Cu" "F.Mask" "F.Paste")
			(net "GND")
		)
		(zone
			(layer "F.Cu")
			(hatch none 0.5)
			(connect_pads
				(clearance 0)
			)
			(min_thickness 0.25)
			(keepout
				(tracks allowed)
				(vias not_allowed)
				(pads allowed)
				(copperpour not_allowed)
				(footprints allowed)
			)
			(placement
				(enabled no)
				(sheetname "")
			)
			(fill
				(thermal_gap 0.5)
				(thermal_bridge_width 0.5)
				(island_removal_mode 0)
			)
			(polygon
				(pts
					(xy 352.3615 -150.114) (xy 352.3615 -150.622) (xy 352.7425 -150.622) (xy 352.7425 -150.114)
				)
			)
		)
		(zone
			(layer "F.Cu")
			(hatch none 0.5)
			(connect_pads
				(clearance 0)
			)
			(min_thickness 0.25)
			(keepout
				(tracks not_allowed)
				(vias allowed)
				(pads allowed)
				(copperpour not_allowed)
				(footprints allowed)
			)
			(placement
				(enabled no)
				(sheetname "")
			)
			(fill
				(thermal_gap 0.5)
				(thermal_bridge_width 0.5)
				(island_removal_mode 0)
			)
			(polygon
				(pts
					(xy 352.7425 -150.114) (xy 352.7425 -150.622) (xy 352.3615 -150.622) (xy 352.3615 -150.114)
				)
			)
		)
	)
	(footprint ""
		(layer "F.Cu")
		(at 463.003392 -37.956998)
		(property "Reference" "C9F9"
			(at 0 0 0)
			(layer "F.SilkS")
			(hide yes)
			(effects
				(font
					(size 1.27 1.27)
				)
			)
		)
		(property "Value" ""
			(at 0 0 0)
			(layer "F.Fab")
			(effects
				(font
					(size 1.27 1.27)
				)
			)
		)
		(duplicate_pad_numbers_are_jumpers no)
		(fp_poly
			(pts
				(xy 0.3048 -0.1016) (xy 0.3048 0.9906) (xy -0.3048 0.9906) (xy -0.3048 -0.1016)
			)
			(stroke
				(width 0)
				(type default)
			)
			(fill no)
			(layer "F.CrtYd")
		)
		(fp_line
			(start -0.3048 -0.1016)
			(end -0.3048 0.9906)
			(stroke
				(width 0.1)
				(type default)
			)
			(layer "F.Fab")
		)
		(fp_line
			(start -0.3048 0.9906)
			(end 0.3048 0.9906)
			(stroke
				(width 0.1)
				(type default)
			)
			(layer "F.Fab")
		)
		(fp_line
			(start 0.3048 -0.1016)
			(end -0.3048 -0.1016)
			(stroke
				(width 0.1)
				(type default)
			)
			(layer "F.Fab")
		)
		(fp_line
			(start 0.3048 0.9906)
			(end 0.3048 -0.1016)
			(stroke
				(width 0.1)
				(type default)
			)
			(layer "F.Fab")
		)
		(pad "1" smd rect
			(at 0 0)
			(size 0.508 0.508)
			(layers "F.Cu" "F.Mask" "F.Paste")
			(net "PWRGD_P1V2_BMC_STBY")
		)
		(pad "2" smd rect
			(at 0 0.889)
			(size 0.508 0.508)
			(layers "F.Cu" "F.Mask" "F.Paste")
			(net "GND")
		)
		(zone
			(layer "F.Cu")
			(hatch none 0.5)
			(connect_pads
				(clearance 0)
			)
			(min_thickness 0.25)
			(keepout
				(tracks allowed)
				(vias not_allowed)
				(pads allowed)
				(copperpour not_allowed)
				(footprints allowed)
			)
			(placement
				(enabled no)
				(sheetname "")
			)
			(fill
				(thermal_gap 0.5)
				(thermal_bridge_width 0.5)
				(island_removal_mode 0)
			)
			(polygon
				(pts
					(xy 462.749392 -37.702998) (xy 463.257392 -37.702998) (xy 463.257392 -37.321998) (xy 462.749392 -37.321998)
				)
			)
		)
		(zone
			(layer "F.Cu")
			(hatch none 0.5)
			(connect_pads
				(clearance 0)
			)
			(min_thickness 0.25)
			(keepout
				(tracks not_allowed)
				(vias allowed)
				(pads allowed)
				(copperpour not_allowed)
				(footprints allowed)
			)
			(placement
				(enabled no)
				(sheetname "")
			)
			(fill
				(thermal_gap 0.5)
				(thermal_bridge_width 0.5)
				(island_removal_mode 0)
			)
			(polygon
				(pts
					(xy 462.749392 -37.321998) (xy 463.257392 -37.321998) (xy 463.257392 -37.702998) (xy 462.749392 -37.702998)
				)
			)
		)
	)
	(footprint ""
		(layer "F.Cu")
		(at 164.084 -64.9224 180)
		(property "Reference" "R4E7"
			(at 0 0 180)
			(layer "F.SilkS")
			(hide yes)
			(effects
				(font
					(size 1.27 1.27)
				)
			)
		)
		(property "Value" ""
			(at 0 0 180)
			(layer "F.Fab")
			(effects
				(font
					(size 1.27 1.27)
				)
			)
		)
		(duplicate_pad_numbers_are_jumpers no)
		(fp_poly
			(pts
				(xy -0.2794 -0.1016) (xy 0.2794 -0.1016) (xy 0.2794 0.9906) (xy -0.2794 0.9906)
			)
			(stroke
				(width 0)
				(type default)
			)
			(fill no)
			(layer "F.CrtYd")
		)
		(fp_line
			(start 0.2794 0.9906)
			(end 0.2794 -0.1016)
			(stroke
				(width 0.1)
				(type default)
			)
			(layer "F.Fab")
		)
		(fp_line
			(start 0.2794 -0.1016)
			(end -0.2794 -0.1016)
			(stroke
				(width 0.1)
				(type default)
			)
			(layer "F.Fab")
		)
		(fp_line
			(start -0.2794 0.9906)
			(end 0.2794 0.9906)
			(stroke
				(width 0.1)
				(type default)
			)
			(layer "F.Fab")
		)
		(fp_line
			(start -0.2794 -0.1016)
			(end -0.2794 0.9906)
			(stroke
				(width 0.1)
				(type default)
			)
			(layer "F.Fab")
		)
		(pad "1" smd rect
			(at 0 0 180)
			(size 0.508 0.508)
			(layers "F.Cu" "F.Mask" "F.Paste")
			(net "VSENSE_PVCCIO_CPU1_AVSP")
		)
		(pad "2" smd rect
			(at 0 0.889 180)
			(size 0.508 0.508)
			(layers "F.Cu" "F.Mask" "F.Paste")
			(net "VR_PVCCIO_CPU1_AVSP")
		)
		(zone
			(layer "F.Cu")
			(hatch none 0.5)
			(connect_pads
				(clearance 0)
			)
			(min_thickness 0.25)
			(keepout
				(tracks not_allowed)
				(vias allowed)
				(pads allowed)
				(copperpour not_allowed)
				(footprints allowed)
			)
			(placement
				(enabled no)
				(sheetname "")
			)
			(fill
				(thermal_gap 0.5)
				(thermal_bridge_width 0.5)
				(island_removal_mode 0)
			)
			(polygon
				(pts
					(xy 164.338 -65.5574) (xy 163.83 -65.5574) (xy 163.83 -65.1764) (xy 164.338 -65.1764)
				)
			)
		)
		(zone
			(layer "F.Cu")
			(hatch none 0.5)
			(connect_pads
				(clearance 0)
			)
			(min_thickness 0.25)
			(keepout
				(tracks allowed)
				(vias not_allowed)
				(pads allowed)
				(copperpour not_allowed)
				(footprints allowed)
			)
			(placement
				(enabled no)
				(sheetname "")
			)
			(fill
				(thermal_gap 0.5)
				(thermal_bridge_width 0.5)
				(island_removal_mode 0)
			)
			(polygon
				(pts
					(xy 164.338 -65.1764) (xy 163.83 -65.1764) (xy 163.83 -65.5574) (xy 164.338 -65.5574)
				)
			)
		)
	)
	(footprint ""
		(layer "F.Cu")
		(at 23.114 -74.549 -90)
		(property "Reference" "R1D37"
			(at 0 0 270)
			(layer "F.SilkS")
			(hide yes)
			(effects
				(font
					(size 1.27 1.27)
				)
			)
		)
		(property "Value" ""
			(at 0 0 270)
			(layer "F.Fab")
			(effects
				(font
					(size 1.27 1.27)
				)
			)
		)
		(duplicate_pad_numbers_are_jumpers no)
		(fp_poly
			(pts
				(xy -0.2794 -0.1016) (xy 0.2794 -0.1016) (xy 0.2794 0.9906) (xy -0.2794 0.9906)
			)
			(stroke
				(width 0)
				(type default)
			)
			(fill no)
			(layer "F.CrtYd")
		)
		(fp_line
			(start -0.2794 0.9906)
			(end 0.2794 0.9906)
			(stroke
				(width 0.1)
				(type default)
			)
			(layer "F.Fab")
		)
		(fp_line
			(start 0.2794 0.9906)
			(end 0.2794 -0.1016)
			(stroke
				(width 0.1)
				(type default)
			)
			(layer "F.Fab")
		)
		(fp_line
			(start -0.2794 -0.1016)
			(end -0.2794 0.9906)
			(stroke
				(width 0.1)
				(type default)
			)
			(layer "F.Fab")
		)
		(fp_line
			(start 0.2794 -0.1016)
			(end -0.2794 -0.1016)
			(stroke
				(width 0.1)
				(type default)
			)
			(layer "F.Fab")
		)
		(pad "1" smd rect
			(at 0 0 270)
			(size 0.508 0.508)
			(layers "F.Cu" "F.Mask" "F.Paste")
			(net "A_HSC_VCAP")
		)
		(pad "2" smd rect
			(at 0 0.889 270)
			(size 0.508 0.508)
			(layers "F.Cu" "F.Mask" "F.Paste")
			(net "A_HSC_ISET")
		)
		(zone
			(layer "F.Cu")
			(hatch none 0.5)
			(connect_pads
				(clearance 0)
			)
			(min_thickness 0.25)
			(keepout
				(tracks not_allowed)
				(vias allowed)
				(pads allowed)
				(copperpour not_allowed)
				(footprints allowed)
			)
			(placement
				(enabled no)
				(sheetname "")
			)
			(fill
				(thermal_gap 0.5)
				(thermal_bridge_width 0.5)
				(island_removal_mode 0)
			)
			(polygon
				(pts
					(xy 22.479 -74.803) (xy 22.479 -74.295) (xy 22.86 -74.295) (xy 22.86 -74.803)
				)
			)
		)
		(zone
			(layer "F.Cu")
			(hatch none 0.5)
			(connect_pads
				(clearance 0)
			)
			(min_thickness 0.25)
			(keepout
				(tracks allowed)
				(vias not_allowed)
				(pads allowed)
				(copperpour not_allowed)
				(footprints allowed)
			)
			(placement
				(enabled no)
				(sheetname "")
			)
			(fill
				(thermal_gap 0.5)
				(thermal_bridge_width 0.5)
				(island_removal_mode 0)
			)
			(polygon
				(pts
					(xy 22.86 -74.803) (xy 22.86 -74.295) (xy 22.479 -74.295) (xy 22.479 -74.803)
				)
			)
		)
	)
)
